# T6G (Grand Teton) — schematic netlist excerpt (pin names and nets, part order shuffled) for the footprints in the layout excerpt that follows; sources: Cadence DE-HDL packaged netlist, KiCad conversion of 04192023_DAF0TMB3IC0_F0TG_MB_C_brd_V02_OCP.brd

C3900  Q_CAP  22UF 4V 20% X6S  pkg C0402  page 72 : A = PVDDCR_SOC_P1 ; B = GND
C6653  Q_CAP_DIFFBUS  DIFF BUS_0.22UF 6.3V 20% X6S  pkg C0201  page 319 : \1\ = P5E_CPU1_P0_TX_BUF_C_DP<12> ; \2\ = P5E_CPU1_P0_TX_BUF_DP<12>
R1085  Q_RES  1K 1% CHIP  pkg 0201LF  page 300 : A = U16_E2 ; B = GND

(kicad_pcb
	(version 20260206)
	(generator "pcbnew")
	(generator_version "10.0")
	(general
		(thickness 1.6)
		(legacy_teardrops no)
	)
	(paper "A4")
	(title_block
		(title "04192023_DAF0TMB3IC0_F0TG_MB_C_brd_V02_OCP.brd")
		(comment 1 "Grand Teton / footprints 143-145 of 8354")
	)
	(layers
		(0 "F.Cu" signal "TOP")
		(4 "In1.Cu" signal "GND")
		(6 "In2.Cu" signal "IN1")
		(8 "In3.Cu" signal "GND1")
		(10 "In4.Cu" signal "IN2")
		(12 "In5.Cu" signal "GND2")
		(14 "In6.Cu" signal "IN3")
		(16 "In7.Cu" signal "GND3")
		(18 "In8.Cu" signal "VCC")
		(20 "In9.Cu" signal "VCC1")
		(22 "In10.Cu" signal "GND4")
		(24 "In11.Cu" signal "IN4")
		(26 "In12.Cu" signal "GND5")
		(28 "In13.Cu" signal "IN5")
		(30 "In14.Cu" signal "GND6")
		(32 "In15.Cu" signal "IN6")
		(34 "In16.Cu" signal "GND7")
		(2 "B.Cu" signal "BOTTOM")
		(9 "F.Adhes" user "F.Adhesive")
		(11 "B.Adhes" user "B.Adhesive")
		(13 "F.Paste" user "Package Geometry/Pastemask Top")
		(15 "B.Paste" user "Package Geometry/Pastemask Bottom")
		(5 "F.SilkS" user "Ref Des/Silkscreen Top")
		(7 "B.SilkS" user "Ref Des/Silkscreen Bottom")
		(1 "F.Mask" user "Board Geometry/Soldermask Top")
		(3 "B.Mask" user "Board Geometry/Soldermask Bottom")
		(17 "Dwgs.User" user "User.Drawings")
		(19 "Cmts.User" user "User.Comments")
		(21 "Eco1.User" user "User.Eco1")
		(23 "Eco2.User" user "User.Eco2")
		(25 "Edge.Cuts" user "Board Geometry/Outline")
		(27 "Margin" user)
		(31 "F.CrtYd" user "Package Geometry/Place Bound Top")
		(29 "B.CrtYd" user "Package Geometry/Place Bound Bottom")
		(35 "F.Fab" user "Ref Des/Assembly Top")
		(33 "B.Fab" user "Ref Des/Assembly Bottom")
	)
	(footprint ""
		(layer "F.Cu")
		(at 85.442044 -408.517344 -90)
		(property "Reference" "C6653"
			(at 0 0 270)
			(layer "F.SilkS")
			(hide yes)
			(effects
				(font
					(size 1.27 1.27)
				)
			)
		)
		(property "Value" ""
			(at 0 0 270)
			(layer "F.Fab")
			(effects
				(font
					(size 1.27 1.27)
				)
			)
		)
		(duplicate_pad_numbers_are_jumpers no)
		(fp_line
			(start -0.299974 0.150114)
			(end -0.299974 -0.150114)
			(stroke
				(width 0.1)
				(type default)
			)
			(layer "F.Fab")
		)
		(fp_line
			(start 0.299974 0.150114)
			(end -0.299974 0.150114)
			(stroke
				(width 0.1)
				(type default)
			)
			(layer "F.Fab")
		)
		(fp_line
			(start -0.299974 -0.150114)
			(end 0.299974 -0.150114)
			(stroke
				(width 0.1)
				(type default)
			)
			(layer "F.Fab")
		)
		(fp_line
			(start 0.299974 -0.150114)
			(end 0.299974 0.150114)
			(stroke
				(width 0.1)
				(type default)
			)
			(layer "F.Fab")
		)
		(pad "1" smd rect
			(at -0.2667 0 270)
			(size 0.3048 0.381)
			(layers "F.Cu" "F.Mask" "F.Paste")
			(net "P5E_CPU1_P0_TX_BUF_C_DP<12>")
		)
		(pad "2" smd rect
			(at 0.2667 0 270)
			(size 0.3048 0.381)
			(layers "F.Cu" "F.Mask" "F.Paste")
			(net "P5E_CPU1_P0_TX_BUF_DP<12>")
		)
	)
	(footprint ""
		(layer "F.Cu")
		(at 420.913306 -432.876198)
		(property "Reference" "R1085"
			(at 0 0 0)
			(layer "F.SilkS")
			(hide yes)
			(effects
				(font
					(size 1.27 1.27)
				)
			)
		)
		(property "Value" ""
			(at 0 0 0)
			(layer "F.Fab")
			(effects
				(font
					(size 1.27 1.27)
				)
			)
		)
		(duplicate_pad_numbers_are_jumpers no)
		(fp_line
			(start -0.32512 -0.175006)
			(end 0.32512 -0.175006)
			(stroke
				(width 0.1)
				(type default)
			)
			(layer "F.Fab")
		)
		(fp_line
			(start -0.32512 0.175006)
			(end -0.32512 -0.175006)
			(stroke
				(width 0.1)
				(type default)
			)
			(layer "F.Fab")
		)
		(fp_line
			(start 0.32512 -0.175006)
			(end 0.32512 0.175006)
			(stroke
				(width 0.1)
				(type default)
			)
			(layer "F.Fab")
		)
		(fp_line
			(start 0.32512 0.175006)
			(end -0.32512 0.175006)
			(stroke
				(width 0.1)
				(type default)
			)
			(layer "F.Fab")
		)
		(pad "1" smd rect
			(at -0.2667 0)
			(size 0.3048 0.381)
			(layers "F.Cu" "F.Mask" "F.Paste")
			(net "U16_E2")
		)
		(pad "2" smd rect
			(at 0.2667 0 180)
			(size 0.3048 0.381)
			(layers "F.Cu" "F.Mask" "F.Paste")
			(net "GND")
		)
	)
	(footprint ""
		(layer "F.Cu")
		(at 116.225828 -256.012442 90)
		(property "Reference" "C3900"
			(at 0 0 90)
			(layer "F.SilkS")
			(hide yes)
			(effects
				(font
					(size 1.27 1.27)
				)
			)
		)
		(property "Value" ""
			(at 0 0 90)
			(layer "F.Fab")
			(effects
				(font
					(size 1.27 1.27)
				)
			)
		)
		(duplicate_pad_numbers_are_jumpers no)
		(fp_line
			(start 0.7874 -0.4064)
			(end 0.7874 0.4064)
			(stroke
				(width 0.1524)
				(type default)
			)
			(layer "F.SilkS")
		)
		(fp_line
			(start -0.7874 -0.4064)
			(end 0.7874 -0.4064)
			(stroke
				(width 0.1524)
				(type default)
			)
			(layer "F.SilkS")
		)
		(fp_line
			(start 0.7874 0.4064)
			(end -0.7874 0.4064)
			(stroke
				(width 0.1524)
				(type default)
			)
			(layer "F.SilkS")
		)
		(fp_line
			(start -0.7874 0.4064)
			(end -0.7874 -0.4064)
			(stroke
				(width 0.1524)
				(type default)
			)
			(layer "F.SilkS")
		)
		(fp_line
			(start -0.12065 -0.305054)
			(end -0.12065 -0.2794)
			(stroke
				(width 0.1)
				(type default)
			)
			(layer "F.Fab")
		)
		(fp_line
			(start -0.67945 -0.305054)
			(end -0.12065 -0.305054)
			(stroke
				(width 0.1)
				(type default)
			)
			(layer "F.Fab")
		)
		(fp_line
			(start 0.67945 -0.3048)
			(end 0.67945 0.3048)
			(stroke
				(width 0.1)
				(type default)
			)
			(layer "F.Fab")
		)
		(fp_line
			(start 0.12065 -0.3048)
			(end 0.67945 -0.3048)
			(stroke
				(width 0.1)
				(type default)
			)
			(layer "F.Fab")
		)
		(fp_line
			(start 0.12065 -0.2794)
			(end 0.12065 -0.3048)
			(stroke
				(width 0.1)
				(type default)
			)
			(layer "F.Fab")
		)
		(fp_line
			(start -0.12065 -0.2794)
			(end 0.12065 -0.2794)
			(stroke
				(width 0.1)
				(type default)
			)
			(layer "F.Fab")
		)
		(fp_line
			(start 0.120396 0.2794)
			(end -0.12065 0.2794)
			(stroke
				(width 0.1)
				(type default)
			)
			(layer "F.Fab")
		)
		(fp_line
			(start -0.12065 0.2794)
			(end -0.12065 0.3048)
			(stroke
				(width 0.1)
				(type default)
			)
			(layer "F.Fab")
		)
		(fp_line
			(start 0.67945 0.3048)
			(end 0.120396 0.3048)
			(stroke
				(width 0.1)
				(type default)
			)
			(layer "F.Fab")
		)
		(fp_line
			(start 0.120396 0.3048)
			(end 0.120396 0.2794)
			(stroke
				(width 0.1)
				(type default)
			)
			(layer "F.Fab")
		)
		(fp_line
			(start -0.12065 0.3048)
			(end -0.67945 0.3048)
			(stroke
				(width 0.1)
				(type default)
			)
			(layer "F.Fab")
		)
		(fp_line
			(start -0.67945 0.3048)
			(end -0.67945 -0.305054)
			(stroke
				(width 0.1)
				(type default)
			)
			(layer "F.Fab")
		)
		(pad "1" smd circle
			(at -0.40005 0 90)
			(size 0 0)
			(layers "F.Cu" "F.Mask" "F.Paste")
			(net "PVDDCR_SOC_P1")
		)
		(pad "2" smd circle
			(at 0.40005 0 90)
			(size 0 0)
			(layers "F.Cu" "F.Mask" "F.Paste")
			(net "GND")
		)
	)
)
